# SCM (Grand Teton) — schematic netlist excerpt (pin names and nets, part order shuffled) for the footprints in the layout excerpt that follows; sources: Cadence DE-HDL packaged netlist, KiCad conversion of 12092022_DA0F0TMDCD0_F0T_Management_Board_D_brd_V3_OCP.brd

R433  Q_RES  33.2 1% CHIP  pkg 0402LF  page 12 : A = SGPIO_DI_1 ; B = SGPIO_BMC_M1_DI
R859  Q_RES  33.2 1% CHIP  pkg 0402LF  page 44 : A = SPI_SYS_R_CLK ; B = SPI_SYS_MUX_CLK

(kicad_pcb
	(version 20260206)
	(generator "pcbnew")
	(generator_version "10.0")
	(general
		(thickness 1.6)
		(legacy_teardrops no)
	)
	(paper "A4")
	(title_block
		(title "12092022_DA0F0TMDCD0_F0T_Management_Board_D_brd_V3_OCP.brd")
		(comment 1 "Grand Teton / footprints 131-132 of 1440")
	)
	(layers
		(0 "F.Cu" signal "TOP")
		(4 "In1.Cu" signal "GND")
		(6 "In2.Cu" signal "IN1")
		(8 "In3.Cu" signal "GND1")
		(10 "In4.Cu" signal "IN2")
		(12 "In5.Cu" signal "VCC")
		(14 "In6.Cu" signal "VCC1")
		(16 "In7.Cu" signal "IN3")
		(18 "In8.Cu" signal "GND2")
		(20 "In9.Cu" signal "IN4")
		(22 "In10.Cu" signal "GND3")
		(2 "B.Cu" signal "BOTTOM")
		(9 "F.Adhes" user "F.Adhesive")
		(11 "B.Adhes" user "B.Adhesive")
		(13 "F.Paste" user "Package Geometry/Pastemask Top")
		(15 "B.Paste" user "Package Geometry/Pastemask Bottom")
		(5 "F.SilkS" user "Ref Des/Silkscreen Top")
		(7 "B.SilkS" user "Ref Des/Silkscreen Bottom")
		(1 "F.Mask" user "Board Geometry/Soldermask Top")
		(3 "B.Mask" user "Board Geometry/Soldermask Bottom")
		(17 "Dwgs.User" user "User.Drawings")
		(19 "Cmts.User" user "User.Comments")
		(21 "Eco1.User" user "User.Eco1")
		(23 "Eco2.User" user "User.Eco2")
		(25 "Edge.Cuts" user "Board Geometry/Outline")
		(27 "Margin" user)
		(31 "F.CrtYd" user "Package Geometry/Place Bound Top")
		(29 "B.CrtYd" user "Package Geometry/Place Bound Bottom")
		(35 "F.Fab" user "Ref Des/Assembly Top")
		(33 "B.Fab" user "Ref Des/Assembly Bottom")
	)
	(footprint ""
		(layer "F.Cu")
		(at 49.2252 -28.2702)
		(property "Reference" "R433"
			(at 0 0 0)
			(layer "F.SilkS")
			(hide yes)
			(effects
				(font
					(size 1.27 1.27)
				)
			)
		)
		(property "Value" ""
			(at 0 0 0)
			(layer "F.Fab")
			(effects
				(font
					(size 1.27 1.27)
				)
			)
		)
		(duplicate_pad_numbers_are_jumpers no)
		(fp_line
			(start -0.7874 -0.4064)
			(end 0.7874 -0.4064)
			(stroke
				(width 0.1524)
				(type default)
			)
			(layer "F.SilkS")
		)
		(fp_line
			(start -0.7874 0.4064)
			(end -0.7874 -0.4064)
			(stroke
				(width 0.1524)
				(type default)
			)
			(layer "F.SilkS")
		)
		(fp_line
			(start 0.7874 -0.4064)
			(end 0.7874 0.4064)
			(stroke
				(width 0.1524)
				(type default)
			)
			(layer "F.SilkS")
		)
		(fp_line
			(start 0.7874 0.4064)
			(end -0.7874 0.4064)
			(stroke
				(width 0.1524)
				(type default)
			)
			(layer "F.SilkS")
		)
		(fp_line
			(start -0.67945 -0.305054)
			(end -0.12065 -0.305054)
			(stroke
				(width 0.1)
				(type default)
			)
			(layer "F.Fab")
		)
		(fp_line
			(start -0.67945 0.3048)
			(end -0.67945 -0.305054)
			(stroke
				(width 0.1)
				(type default)
			)
			(layer "F.Fab")
		)
		(fp_line
			(start -0.12065 -0.305054)
			(end -0.12065 -0.2794)
			(stroke
				(width 0.1)
				(type default)
			)
			(layer "F.Fab")
		)
		(fp_line
			(start -0.12065 -0.2794)
			(end 0.12065 -0.2794)
			(stroke
				(width 0.1)
				(type default)
			)
			(layer "F.Fab")
		)
		(fp_line
			(start -0.12065 0.2794)
			(end -0.12065 0.3048)
			(stroke
				(width 0.1)
				(type default)
			)
			(layer "F.Fab")
		)
		(fp_line
			(start -0.12065 0.3048)
			(end -0.67945 0.3048)
			(stroke
				(width 0.1)
				(type default)
			)
			(layer "F.Fab")
		)
		(fp_line
			(start 0.120396 0.2794)
			(end -0.12065 0.2794)
			(stroke
				(width 0.1)
				(type default)
			)
			(layer "F.Fab")
		)
		(fp_line
			(start 0.120396 0.3048)
			(end 0.120396 0.2794)
			(stroke
				(width 0.1)
				(type default)
			)
			(layer "F.Fab")
		)
		(fp_line
			(start 0.12065 -0.3048)
			(end 0.67945 -0.3048)
			(stroke
				(width 0.1)
				(type default)
			)
			(layer "F.Fab")
		)
		(fp_line
			(start 0.12065 -0.2794)
			(end 0.12065 -0.3048)
			(stroke
				(width 0.1)
				(type default)
			)
			(layer "F.Fab")
		)
		(fp_line
			(start 0.67945 -0.3048)
			(end 0.67945 0.3048)
			(stroke
				(width 0.1)
				(type default)
			)
			(layer "F.Fab")
		)
		(fp_line
			(start 0.67945 0.3048)
			(end 0.120396 0.3048)
			(stroke
				(width 0.1)
				(type default)
			)
			(layer "F.Fab")
		)
		(pad "1" smd circle
			(at -0.40005 0)
			(size 0 0)
			(layers "F.Cu" "F.Mask" "F.Paste")
			(net "SGPIO_DI_1")
		)
		(pad "2" smd circle
			(at 0.40005 0)
			(size 0 0)
			(layers "F.Cu" "F.Mask" "F.Paste")
			(net "SGPIO_BMC_M1_DI")
		)
	)
	(footprint ""
		(layer "F.Cu")
		(at 57.531 -102.9462 -90)
		(property "Reference" "R859"
			(at 0 0 270)
			(layer "F.SilkS")
			(hide yes)
			(effects
				(font
					(size 1.27 1.27)
				)
			)
		)
		(property "Value" ""
			(at 0 0 270)
			(layer "F.Fab")
			(effects
				(font
					(size 1.27 1.27)
				)
			)
		)
		(duplicate_pad_numbers_are_jumpers no)
		(fp_line
			(start -0.7874 0.4064)
			(end -0.7874 -0.4064)
			(stroke
				(width 0.1524)
				(type default)
			)
			(layer "F.SilkS")
		)
		(fp_line
			(start 0.7874 0.4064)
			(end -0.7874 0.4064)
			(stroke
				(width 0.1524)
				(type default)
			)
			(layer "F.SilkS")
		)
		(fp_line
			(start -0.7874 -0.4064)
			(end 0.7874 -0.4064)
			(stroke
				(width 0.1524)
				(type default)
			)
			(layer "F.SilkS")
		)
		(fp_line
			(start 0.7874 -0.4064)
			(end 0.7874 0.4064)
			(stroke
				(width 0.1524)
				(type default)
			)
			(layer "F.SilkS")
		)
		(fp_line
			(start -0.67945 0.3048)
			(end -0.67945 -0.305054)
			(stroke
				(width 0.1)
				(type default)
			)
			(layer "F.Fab")
		)
		(fp_line
			(start -0.12065 0.3048)
			(end -0.67945 0.3048)
			(stroke
				(width 0.1)
				(type default)
			)
			(layer "F.Fab")
		)
		(fp_line
			(start 0.120396 0.3048)
			(end 0.120396 0.2794)
			(stroke
				(width 0.1)
				(type default)
			)
			(layer "F.Fab")
		)
		(fp_line
			(start 0.67945 0.3048)
			(end 0.120396 0.3048)
			(stroke
				(width 0.1)
				(type default)
			)
			(layer "F.Fab")
		)
		(fp_line
			(start -0.12065 0.2794)
			(end -0.12065 0.3048)
			(stroke
				(width 0.1)
				(type default)
			)
			(layer "F.Fab")
		)
		(fp_line
			(start 0.120396 0.2794)
			(end -0.12065 0.2794)
			(stroke
				(width 0.1)
				(type default)
			)
			(layer "F.Fab")
		)
		(fp_line
			(start -0.12065 -0.2794)
			(end 0.12065 -0.2794)
			(stroke
				(width 0.1)
				(type default)
			)
			(layer "F.Fab")
		)
		(fp_line
			(start 0.12065 -0.2794)
			(end 0.12065 -0.3048)
			(stroke
				(width 0.1)
				(type default)
			)
			(layer "F.Fab")
		)
		(fp_line
			(start 0.12065 -0.3048)
			(end 0.67945 -0.3048)
			(stroke
				(width 0.1)
				(type default)
			)
			(layer "F.Fab")
		)
		(fp_line
			(start 0.67945 -0.3048)
			(end 0.67945 0.3048)
			(stroke
				(width 0.1)
				(type default)
			)
			(layer "F.Fab")
		)
		(fp_line
			(start -0.67945 -0.305054)
			(end -0.12065 -0.305054)
			(stroke
				(width 0.1)
				(type default)
			)
			(layer "F.Fab")
		)
		(fp_line
			(start -0.12065 -0.305054)
			(end -0.12065 -0.2794)
			(stroke
				(width 0.1)
				(type default)
			)
			(layer "F.Fab")
		)
		(pad "1" smd circle
			(at -0.40005 0 270)
			(size 0 0)
			(layers "F.Cu" "F.Mask" "F.Paste")
			(net "SPI_SYS_R_CLK")
		)
		(pad "2" smd circle
			(at 0.40005 0 270)
			(size 0 0)
			(layers "F.Cu" "F.Mask" "F.Paste")
			(net "SPI_SYS_MUX_CLK")
		)
	)
)
